(kicad_pcb
	(version 20260206)
	(generator "pcbnew")
	(generator_version "10.0")
	(general
		(thickness 1.6)
		(legacy_teardrops no)
	)
	(paper "A4")
	(title_block
		(title "01162023_DA0F0TEBIF0_F0T_Expander_BD_F_brd_V02_OCP.brd")
		(comment 1 "Grand Teton / footprints 6512-6517 of 9728")
	)
	(layers
		(0 "F.Cu" signal "TOP")
		(4 "In1.Cu" signal "GND")
		(6 "In2.Cu" signal "VCC")
		(8 "In3.Cu" signal "VCC1")
		(10 "In4.Cu" signal "GND1")
		(12 "In5.Cu" signal "IN1")
		(14 "In6.Cu" signal "GND2")
		(16 "In7.Cu" signal "IN2")
		(18 "In8.Cu" signal "GND3")
		(20 "In9.Cu" signal "IN3")
		(22 "In10.Cu" signal "GND4")
		(24 "In11.Cu" signal "IN4")
		(26 "In12.Cu" signal "GND5")
		(28 "In13.Cu" signal "IN5")
		(30 "In14.Cu" signal "GND6")
		(32 "In15.Cu" signal "IN6")
		(34 "In16.Cu" signal "GND7")
		(2 "B.Cu" signal "BOTTOM")
		(9 "F.Adhes" user "F.Adhesive")
		(11 "B.Adhes" user "B.Adhesive")
		(13 "F.Paste" user "Package Geometry/Pastemask Top")
		(15 "B.Paste" user "Package Geometry/Pastemask Bottom")
		(5 "F.SilkS" user "Ref Des/Silkscreen Top")
		(7 "B.SilkS" user "Ref Des/Silkscreen Bottom")
		(1 "F.Mask" user "Board Geometry/Soldermask Top")
		(3 "B.Mask" user "Board Geometry/Soldermask Bottom")
		(17 "Dwgs.User" user "User.Drawings")
		(19 "Cmts.User" user "User.Comments")
		(21 "Eco1.User" user "User.Eco1")
		(23 "Eco2.User" user "User.Eco2")
		(25 "Edge.Cuts" user "Board Geometry/Outline")
		(27 "Margin" user)
		(31 "F.CrtYd" user "Package Geometry/Place Bound Top")
		(29 "B.CrtYd" user "Package Geometry/Place Bound Bottom")
		(35 "F.Fab" user "Ref Des/Assembly Top")
		(33 "B.Fab" user "Ref Des/Assembly Bottom")
	)
	(footprint ""
		(layer "F.Cu")
		(at 122.809254 -27.04973 180)
		(property "Reference" "C2767"
			(at 0 0 180)
			(layer "F.SilkS")
			(hide yes)
			(effects
				(font
					(size 1.27 1.27)
				)
			)
		)
		(property "Value" ""
			(at 0 0 180)
			(layer "F.Fab")
			(effects
				(font
					(size 1.27 1.27)
				)
			)
		)
		(duplicate_pad_numbers_are_jumpers no)
		(fp_line
			(start 0.7874 0.4064)
			(end -0.7874 0.4064)
			(stroke
				(width 0.1524)
				(type default)
			)
			(layer "F.SilkS")
		)
		(fp_line
			(start 0.7874 -0.4064)
			(end 0.7874 0.4064)
			(stroke
				(width 0.1524)
				(type default)
			)
			(layer "F.SilkS")
		)
		(fp_line
			(start -0.7874 0.4064)
			(end -0.7874 -0.4064)
			(stroke
				(width 0.1524)
				(type default)
			)
			(layer "F.SilkS")
		)
		(fp_line
			(start -0.7874 -0.4064)
			(end 0.7874 -0.4064)
			(stroke
				(width 0.1524)
				(type default)
			)
			(layer "F.SilkS")
		)
		(fp_line
			(start 0.67945 0.3048)
			(end 0.120396 0.3048)
			(stroke
				(width 0.1)
				(type default)
			)
			(layer "F.Fab")
		)
		(fp_line
			(start 0.67945 -0.3048)
			(end 0.67945 0.3048)
			(stroke
				(width 0.1)
				(type default)
			)
			(layer "F.Fab")
		)
		(fp_line
			(start 0.12065 -0.2794)
			(end 0.12065 -0.3048)
			(stroke
				(width 0.1)
				(type default)
			)
			(layer "F.Fab")
		)
		(fp_line
			(start 0.12065 -0.3048)
			(end 0.67945 -0.3048)
			(stroke
				(width 0.1)
				(type default)
			)
			(layer "F.Fab")
		)
		(fp_line
			(start 0.120396 0.3048)
			(end 0.120396 0.2794)
			(stroke
				(width 0.1)
				(type default)
			)
			(layer "F.Fab")
		)
		(fp_line
			(start 0.120396 0.2794)
			(end -0.12065 0.2794)
			(stroke
				(width 0.1)
				(type default)
			)
			(layer "F.Fab")
		)
		(fp_line
			(start -0.12065 0.3048)
			(end -0.67945 0.3048)
			(stroke
				(width 0.1)
				(type default)
			)
			(layer "F.Fab")
		)
		(fp_line
			(start -0.12065 0.2794)
			(end -0.12065 0.3048)
			(stroke
				(width 0.1)
				(type default)
			)
			(layer "F.Fab")
		)
		(fp_line
			(start -0.12065 -0.2794)
			(end 0.12065 -0.2794)
			(stroke
				(width 0.1)
				(type default)
			)
			(layer "F.Fab")
		)
		(fp_line
			(start -0.12065 -0.305054)
			(end -0.12065 -0.2794)
			(stroke
				(width 0.1)
				(type default)
			)
			(layer "F.Fab")
		)
		(fp_line
			(start -0.67945 0.3048)
			(end -0.67945 -0.305054)
			(stroke
				(width 0.1)
				(type default)
			)
			(layer "F.Fab")
		)
		(fp_line
			(start -0.67945 -0.305054)
			(end -0.12065 -0.305054)
			(stroke
				(width 0.1)
				(type default)
			)
			(layer "F.Fab")
		)
		(pad "1" smd circle
			(at -0.40005 0 180)
			(size 0 0)
			(layers "F.Cu" "F.Mask" "F.Paste")
			(net "PRSNT_SSD4_R_N")
		)
		(pad "2" smd circle
			(at 0.40005 0 180)
			(size 0 0)
			(layers "F.Cu" "F.Mask" "F.Paste")
			(net "GND")
		)
	)
	(footprint ""
		(layer "F.Cu")
		(at 252.714506 -66.32194 90)
		(property "Reference" "R5990"
			(at 0 0 90)
			(layer "F.SilkS")
			(hide yes)
			(effects
				(font
					(size 1.27 1.27)
				)
			)
		)
		(property "Value" ""
			(at 0 0 90)
			(layer "F.Fab")
			(effects
				(font
					(size 1.27 1.27)
				)
			)
		)
		(duplicate_pad_numbers_are_jumpers no)
		(fp_line
			(start 0.7874 -0.4064)
			(end 0.7874 0.4064)
			(stroke
				(width 0.1524)
				(type default)
			)
			(layer "F.SilkS")
		)
		(fp_line
			(start -0.7874 -0.4064)
			(end 0.7874 -0.4064)
			(stroke
				(width 0.1524)
				(type default)
			)
			(layer "F.SilkS")
		)
		(fp_line
			(start 0.7874 0.4064)
			(end -0.7874 0.4064)
			(stroke
				(width 0.1524)
				(type default)
			)
			(layer "F.SilkS")
		)
		(fp_line
			(start -0.7874 0.4064)
			(end -0.7874 -0.4064)
			(stroke
				(width 0.1524)
				(type default)
			)
			(layer "F.SilkS")
		)
		(fp_line
			(start -0.12065 -0.305054)
			(end -0.12065 -0.2794)
			(stroke
				(width 0.1)
				(type default)
			)
			(layer "F.Fab")
		)
		(fp_line
			(start -0.67945 -0.305054)
			(end -0.12065 -0.305054)
			(stroke
				(width 0.1)
				(type default)
			)
			(layer "F.Fab")
		)
		(fp_line
			(start 0.67945 -0.3048)
			(end 0.67945 0.3048)
			(stroke
				(width 0.1)
				(type default)
			)
			(layer "F.Fab")
		)
		(fp_line
			(start 0.12065 -0.3048)
			(end 0.67945 -0.3048)
			(stroke
				(width 0.1)
				(type default)
			)
			(layer "F.Fab")
		)
		(fp_line
			(start 0.12065 -0.2794)
			(end 0.12065 -0.3048)
			(stroke
				(width 0.1)
				(type default)
			)
			(layer "F.Fab")
		)
		(fp_line
			(start -0.12065 -0.2794)
			(end 0.12065 -0.2794)
			(stroke
				(width 0.1)
				(type default)
			)
			(layer "F.Fab")
		)
		(fp_line
			(start 0.120396 0.2794)
			(end -0.12065 0.2794)
			(stroke
				(width 0.1)
				(type default)
			)
			(layer "F.Fab")
		)
		(fp_line
			(start -0.12065 0.2794)
			(end -0.12065 0.3048)
			(stroke
				(width 0.1)
				(type default)
			)
			(layer "F.Fab")
		)
		(fp_line
			(start 0.67945 0.3048)
			(end 0.120396 0.3048)
			(stroke
				(width 0.1)
				(type default)
			)
			(layer "F.Fab")
		)
		(fp_line
			(start 0.120396 0.3048)
			(end 0.120396 0.2794)
			(stroke
				(width 0.1)
				(type default)
			)
			(layer "F.Fab")
		)
		(fp_line
			(start -0.12065 0.3048)
			(end -0.67945 0.3048)
			(stroke
				(width 0.1)
				(type default)
			)
			(layer "F.Fab")
		)
		(fp_line
			(start -0.67945 0.3048)
			(end -0.67945 -0.305054)
			(stroke
				(width 0.1)
				(type default)
			)
			(layer "F.Fab")
		)
		(pad "1" smd circle
			(at -0.40005 0 90)
			(size 0 0)
			(layers "F.Cu" "F.Mask" "F.Paste")
			(net "SSD8_PWR_EN_R")
		)
		(pad "2" smd circle
			(at 0.40005 0 90)
			(size 0 0)
			(layers "F.Cu" "F.Mask" "F.Paste")
			(net "P12V_SSD8_CO_EN")
		)
	)
	(footprint ""
		(layer "F.Cu")
		(at 202.036172 -306.049172 90)
		(property "Reference" "R3930"
			(at 0 0 90)
			(layer "F.SilkS")
			(hide yes)
			(effects
				(font
					(size 1.27 1.27)
				)
			)
		)
		(property "Value" ""
			(at 0 0 90)
			(layer "F.Fab")
			(effects
				(font
					(size 1.27 1.27)
				)
			)
		)
		(duplicate_pad_numbers_are_jumpers no)
		(fp_line
			(start 0.7874 -0.4064)
			(end 0.7874 0.4064)
			(stroke
				(width 0.1524)
				(type default)
			)
			(layer "F.SilkS")
		)
		(fp_line
			(start -0.7874 -0.4064)
			(end 0.7874 -0.4064)
			(stroke
				(width 0.1524)
				(type default)
			)
			(layer "F.SilkS")
		)
		(fp_line
			(start 0.7874 0.4064)
			(end -0.7874 0.4064)
			(stroke
				(width 0.1524)
				(type default)
			)
			(layer "F.SilkS")
		)
		(fp_line
			(start -0.7874 0.4064)
			(end -0.7874 -0.4064)
			(stroke
				(width 0.1524)
				(type default)
			)
			(layer "F.SilkS")
		)
		(fp_line
			(start -0.12065 -0.305054)
			(end -0.12065 -0.2794)
			(stroke
				(width 0.1)
				(type default)
			)
			(layer "F.Fab")
		)
		(fp_line
			(start -0.67945 -0.305054)
			(end -0.12065 -0.305054)
			(stroke
				(width 0.1)
				(type default)
			)
			(layer "F.Fab")
		)
		(fp_line
			(start 0.67945 -0.3048)
			(end 0.67945 0.3048)
			(stroke
				(width 0.1)
				(type default)
			)
			(layer "F.Fab")
		)
		(fp_line
			(start 0.12065 -0.3048)
			(end 0.67945 -0.3048)
			(stroke
				(width 0.1)
				(type default)
			)
			(layer "F.Fab")
		)
		(fp_line
			(start 0.12065 -0.2794)
			(end 0.12065 -0.3048)
			(stroke
				(width 0.1)
				(type default)
			)
			(layer "F.Fab")
		)
		(fp_line
			(start -0.12065 -0.2794)
			(end 0.12065 -0.2794)
			(stroke
				(width 0.1)
				(type default)
			)
			(layer "F.Fab")
		)
		(fp_line
			(start 0.120396 0.2794)
			(end -0.12065 0.2794)
			(stroke
				(width 0.1)
				(type default)
			)
			(layer "F.Fab")
		)
		(fp_line
			(start -0.12065 0.2794)
			(end -0.12065 0.3048)
			(stroke
				(width 0.1)
				(type default)
			)
			(layer "F.Fab")
		)
		(fp_line
			(start 0.67945 0.3048)
			(end 0.120396 0.3048)
			(stroke
				(width 0.1)
				(type default)
			)
			(layer "F.Fab")
		)
		(fp_line
			(start 0.120396 0.3048)
			(end 0.120396 0.2794)
			(stroke
				(width 0.1)
				(type default)
			)
			(layer "F.Fab")
		)
		(fp_line
			(start -0.12065 0.3048)
			(end -0.67945 0.3048)
			(stroke
				(width 0.1)
				(type default)
			)
			(layer "F.Fab")
		)
		(fp_line
			(start -0.67945 0.3048)
			(end -0.67945 -0.305054)
			(stroke
				(width 0.1)
				(type default)
			)
			(layer "F.Fab")
		)
		(pad "1" smd circle
			(at -0.40005 0 90)
			(size 0 0)
			(layers "F.Cu" "F.Mask" "F.Paste")
			(net "SMB_PEX1_SLAVE_SCL")
		)
		(pad "2" smd circle
			(at 0.40005 0 90)
			(size 0 0)
			(layers "F.Cu" "F.Mask" "F.Paste")
			(net "SMB_PEX1_R_SCL")
		)
	)
	(footprint ""
		(layer "F.Cu")
		(at 202.652376 -364.885986 180)
		(property "Reference" "PC3"
			(at 0 0 180)
			(layer "F.SilkS")
			(hide yes)
			(effects
				(font
					(size 1.27 1.27)
				)
			)
		)
		(property "Value" ""
			(at 0 0 180)
			(layer "F.Fab")
			(effects
				(font
					(size 1.27 1.27)
				)
			)
		)
		(duplicate_pad_numbers_are_jumpers no)
		(fp_line
			(start 0.7874 0.4064)
			(end -0.7874 0.4064)
			(stroke
				(width 0.1524)
				(type default)
			)
			(layer "F.SilkS")
		)
		(fp_line
			(start 0.7874 -0.4064)
			(end 0.7874 0.4064)
			(stroke
				(width 0.1524)
				(type default)
			)
			(layer "F.SilkS")
		)
		(fp_line
			(start -0.7874 0.4064)
			(end -0.7874 -0.4064)
			(stroke
				(width 0.1524)
				(type default)
			)
			(layer "F.SilkS")
		)
		(fp_line
			(start -0.7874 -0.4064)
			(end 0.7874 -0.4064)
			(stroke
				(width 0.1524)
				(type default)
			)
			(layer "F.SilkS")
		)
		(fp_line
			(start 0.67945 0.3048)
			(end 0.120396 0.3048)
			(stroke
				(width 0.1)
				(type default)
			)
			(layer "F.Fab")
		)
		(fp_line
			(start 0.67945 -0.3048)
			(end 0.67945 0.3048)
			(stroke
				(width 0.1)
				(type default)
			)
			(layer "F.Fab")
		)
		(fp_line
			(start 0.12065 -0.2794)
			(end 0.12065 -0.3048)
			(stroke
				(width 0.1)
				(type default)
			)
			(layer "F.Fab")
		)
		(fp_line
			(start 0.12065 -0.3048)
			(end 0.67945 -0.3048)
			(stroke
				(width 0.1)
				(type default)
			)
			(layer "F.Fab")
		)
		(fp_line
			(start 0.120396 0.3048)
			(end 0.120396 0.2794)
			(stroke
				(width 0.1)
				(type default)
			)
			(layer "F.Fab")
		)
		(fp_line
			(start 0.120396 0.2794)
			(end -0.12065 0.2794)
			(stroke
				(width 0.1)
				(type default)
			)
			(layer "F.Fab")
		)
		(fp_line
			(start -0.12065 0.3048)
			(end -0.67945 0.3048)
			(stroke
				(width 0.1)
				(type default)
			)
			(layer "F.Fab")
		)
		(fp_line
			(start -0.12065 0.2794)
			(end -0.12065 0.3048)
			(stroke
				(width 0.1)
				(type default)
			)
			(layer "F.Fab")
		)
		(fp_line
			(start -0.12065 -0.2794)
			(end 0.12065 -0.2794)
			(stroke
				(width 0.1)
				(type default)
			)
			(layer "F.Fab")
		)
		(fp_line
			(start -0.12065 -0.305054)
			(end -0.12065 -0.2794)
			(stroke
				(width 0.1)
				(type default)
			)
			(layer "F.Fab")
		)
		(fp_line
			(start -0.67945 0.3048)
			(end -0.67945 -0.305054)
			(stroke
				(width 0.1)
				(type default)
			)
			(layer "F.Fab")
		)
		(fp_line
			(start -0.67945 -0.305054)
			(end -0.12065 -0.305054)
			(stroke
				(width 0.1)
				(type default)
			)
			(layer "F.Fab")
		)
		(pad "1" smd circle
			(at -0.40005 0 180)
			(size 0 0)
			(layers "F.Cu" "F.Mask" "F.Paste")
			(net "HSC_VOSEN")
		)
		(pad "2" smd circle
			(at 0.40005 0 180)
			(size 0 0)
			(layers "F.Cu" "F.Mask" "F.Paste")
			(net "AGND_HSC")
		)
	)
	(footprint ""
		(layer "F.Cu")
		(at 229.594664 -204.44206 -90)
		(property "Reference" "R458"
			(at 0 0 270)
			(layer "F.SilkS")
			(hide yes)
			(effects
				(font
					(size 1.27 1.27)
				)
			)
		)
		(property "Value" ""
			(at 0 0 270)
			(layer "F.Fab")
			(effects
				(font
					(size 1.27 1.27)
				)
			)
		)
		(duplicate_pad_numbers_are_jumpers no)
		(fp_line
			(start -0.7874 0.4064)
			(end -0.7874 -0.4064)
			(stroke
				(width 0.1524)
				(type default)
			)
			(layer "F.SilkS")
		)
		(fp_line
			(start 0.7874 0.4064)
			(end -0.7874 0.4064)
			(stroke
				(width 0.1524)
				(type default)
			)
			(layer "F.SilkS")
		)
		(fp_line
			(start -0.7874 -0.4064)
			(end 0.7874 -0.4064)
			(stroke
				(width 0.1524)
				(type default)
			)
			(layer "F.SilkS")
		)
		(fp_line
			(start 0.7874 -0.4064)
			(end 0.7874 0.4064)
			(stroke
				(width 0.1524)
				(type default)
			)
			(layer "F.SilkS")
		)
		(fp_line
			(start -0.67945 0.3048)
			(end -0.67945 -0.305054)
			(stroke
				(width 0.1)
				(type default)
			)
			(layer "F.Fab")
		)
		(fp_line
			(start -0.12065 0.3048)
			(end -0.67945 0.3048)
			(stroke
				(width 0.1)
				(type default)
			)
			(layer "F.Fab")
		)
		(fp_line
			(start 0.120396 0.3048)
			(end 0.120396 0.2794)
			(stroke
				(width 0.1)
				(type default)
			)
			(layer "F.Fab")
		)
		(fp_line
			(start 0.67945 0.3048)
			(end 0.120396 0.3048)
			(stroke
				(width 0.1)
				(type default)
			)
			(layer "F.Fab")
		)
		(fp_line
			(start -0.12065 0.2794)
			(end -0.12065 0.3048)
			(stroke
				(width 0.1)
				(type default)
			)
			(layer "F.Fab")
		)
		(fp_line
			(start 0.120396 0.2794)
			(end -0.12065 0.2794)
			(stroke
				(width 0.1)
				(type default)
			)
			(layer "F.Fab")
		)
		(fp_line
			(start -0.12065 -0.2794)
			(end 0.12065 -0.2794)
			(stroke
				(width 0.1)
				(type default)
			)
			(layer "F.Fab")
		)
		(fp_line
			(start 0.12065 -0.2794)
			(end 0.12065 -0.3048)
			(stroke
				(width 0.1)
				(type default)
			)
			(layer "F.Fab")
		)
		(fp_line
			(start 0.12065 -0.3048)
			(end 0.67945 -0.3048)
			(stroke
				(width 0.1)
				(type default)
			)
			(layer "F.Fab")
		)
		(fp_line
			(start 0.67945 -0.3048)
			(end 0.67945 0.3048)
			(stroke
				(width 0.1)
				(type default)
			)
			(layer "F.Fab")
		)
		(fp_line
			(start -0.67945 -0.305054)
			(end -0.12065 -0.305054)
			(stroke
				(width 0.1)
				(type default)
			)
			(layer "F.Fab")
		)
		(fp_line
			(start -0.12065 -0.305054)
			(end -0.12065 -0.2794)
			(stroke
				(width 0.1)
				(type default)
			)
			(layer "F.Fab")
		)
		(pad "1" smd circle
			(at -0.40005 0 270)
			(size 0 0)
			(layers "F.Cu" "F.Mask" "F.Paste")
			(net "SPI_BIC1_CS0_N")
		)
		(pad "2" smd circle
			(at 0.40005 0 270)
			(size 0 0)
			(layers "F.Cu" "F.Mask" "F.Paste")
			(net "SPI_BIC1_CS0_R_N")
		)
	)
	(footprint ""
		(layer "F.Cu")
		(at 419.089586 -239.302544 180)
		(property "Reference" "R6619"
			(at 0 0 180)
			(layer "F.SilkS")
			(hide yes)
			(effects
				(font
					(size 1.27 1.27)
				)
			)
		)
		(property "Value" ""
			(at 0 0 180)
			(layer "F.Fab")
			(effects
				(font
					(size 1.27 1.27)
				)
			)
		)
		(duplicate_pad_numbers_are_jumpers no)
		(fp_line
			(start 0.7874 0.4064)
			(end -0.7874 0.4064)
			(stroke
				(width 0.1524)
				(type default)
			)
			(layer "F.SilkS")
		)
		(fp_line
			(start 0.7874 -0.4064)
			(end 0.7874 0.4064)
			(stroke
				(width 0.1524)
				(type default)
			)
			(layer "F.SilkS")
		)
		(fp_line
			(start -0.7874 0.4064)
			(end -0.7874 -0.4064)
			(stroke
				(width 0.1524)
				(type default)
			)
			(layer "F.SilkS")
		)
		(fp_line
			(start -0.7874 -0.4064)
			(end 0.7874 -0.4064)
			(stroke
				(width 0.1524)
				(type default)
			)
			(layer "F.SilkS")
		)
		(fp_line
			(start 0.67945 0.3048)
			(end 0.120396 0.3048)
			(stroke
				(width 0.1)
				(type default)
			)
			(layer "F.Fab")
		)
		(fp_line
			(start 0.67945 -0.3048)
			(end 0.67945 0.3048)
			(stroke
				(width 0.1)
				(type default)
			)
			(layer "F.Fab")
		)
		(fp_line
			(start 0.12065 -0.2794)
			(end 0.12065 -0.3048)
			(stroke
				(width 0.1)
				(type default)
			)
			(layer "F.Fab")
		)
		(fp_line
			(start 0.12065 -0.3048)
			(end 0.67945 -0.3048)
			(stroke
				(width 0.1)
				(type default)
			)
			(layer "F.Fab")
		)
		(fp_line
			(start 0.120396 0.3048)
			(end 0.120396 0.2794)
			(stroke
				(width 0.1)
				(type default)
			)
			(layer "F.Fab")
		)
		(fp_line
			(start 0.120396 0.2794)
			(end -0.12065 0.2794)
			(stroke
				(width 0.1)
				(type default)
			)
			(layer "F.Fab")
		)
		(fp_line
			(start -0.12065 0.3048)
			(end -0.67945 0.3048)
			(stroke
				(width 0.1)
				(type default)
			)
			(layer "F.Fab")
		)
		(fp_line
			(start -0.12065 0.2794)
			(end -0.12065 0.3048)
			(stroke
				(width 0.1)
				(type default)
			)
			(layer "F.Fab")
		)
		(fp_line
			(start -0.12065 -0.2794)
			(end 0.12065 -0.2794)
			(stroke
				(width 0.1)
				(type default)
			)
			(layer "F.Fab")
		)
		(fp_line
			(start -0.12065 -0.305054)
			(end -0.12065 -0.2794)
			(stroke
				(width 0.1)
				(type default)
			)
			(layer "F.Fab")
		)
		(fp_line
			(start -0.67945 0.3048)
			(end -0.67945 -0.305054)
			(stroke
				(width 0.1)
				(type default)
			)
			(layer "F.Fab")
		)
		(fp_line
			(start -0.67945 -0.305054)
			(end -0.12065 -0.305054)
			(stroke
				(width 0.1)
				(type default)
			)
			(layer "F.Fab")
		)
		(pad "1" smd circle
			(at -0.40005 0 180)
			(size 0 0)
			(layers "F.Cu" "F.Mask" "F.Paste")
			(net "UART_PEX2_SDB_R_RX")
		)
		(pad "2" smd circle
			(at 0.40005 0 180)
			(size 0 0)
			(layers "F.Cu" "F.Mask" "F.Paste")
			(net "UART_PEX2_SDB_R1_RX")
		)
	)
)
